(kicad_pcb
	(version 20260206)
	(generator "pcbnew")
	(generator_version "10.0")
	(general
		(thickness 1.6)
		(legacy_teardrops no)
	)
	(paper "A4")
	(title_block
		(title "pdpb — Lightning_PDPB_BRD.brd")
		(comment 1 "Lightning (Wiwynn / Facebook NVMe JBOF) / footprints 493-497 of 1140")
	)
	(layers
		(0 "F.Cu" signal "TOP")
		(4 "In1.Cu" signal "L2GND")
		(6 "In2.Cu" signal "L3")
		(8 "In3.Cu" signal "L4VCC")
		(10 "In4.Cu" signal "L5VCC")
		(12 "In5.Cu" signal "L6")
		(14 "In6.Cu" signal "L7GND")
		(2 "B.Cu" signal "BOTTOM")
		(9 "F.Adhes" user "F.Adhesive")
		(11 "B.Adhes" user "B.Adhesive")
		(13 "F.Paste" user "Package Geometry/Pastemask Top")
		(15 "B.Paste" user "Package Geometry/Pastemask Bottom")
		(5 "F.SilkS" user "Ref Des/Silkscreen Top")
		(7 "B.SilkS" user "Ref Des/Silkscreen Bottom")
		(1 "F.Mask" user "Board Geometry/Soldermask Top")
		(3 "B.Mask" user "Board Geometry/Soldermask Bottom")
		(17 "Dwgs.User" user "User.Drawings")
		(19 "Cmts.User" user "User.Comments")
		(21 "Eco1.User" user "User.Eco1")
		(23 "Eco2.User" user "User.Eco2")
		(25 "Edge.Cuts" user "Board Geometry/Outline")
		(27 "Margin" user)
		(31 "F.CrtYd" user "Package Geometry/Place Bound Top")
		(29 "B.CrtYd" user "Package Geometry/Place Bound Bottom")
		(35 "F.Fab" user "Ref Des/Assembly Top")
		(33 "B.Fab" user "Ref Des/Assembly Bottom")
	)
	(footprint ""
		(layer "F.Cu")
		(at 38.481 -245.745)
		(property "Reference" "Q63"
			(at 0 0 0)
			(layer "F.SilkS")
			(hide yes)
			(effects
				(font
					(size 1.27 1.27)
				)
			)
		)
		(property "Value" "2N7002A-7-GP"
			(at 0.127 -8.9662 0)
			(unlocked yes)
			(layer "F.Fab")
			(hide yes)
			(effects
				(font
					(size 1.016 1.016)
					(thickness 0.1524)
				)
			)
		)
		(property "Device Type" "SOT23DGS2D4H48"
			(at 0.127 -10.4902 0)
			(unlocked yes)
			(layer "F.Fab")
			(hide yes)
			(effects
				(font
					(size 1.016 1.016)
					(thickness 0.1524)
				)
			)
		)
		(duplicate_pad_numbers_are_jumpers no)
		(fp_line
			(start -1.651 -1.778)
			(end -1.651 1.778)
			(stroke
				(width 0.1524)
				(type default)
			)
			(layer "F.SilkS")
		)
		(fp_line
			(start -1.651 1.778)
			(end 1.651 1.778)
			(stroke
				(width 0.1524)
				(type default)
			)
			(layer "F.SilkS")
		)
		(fp_line
			(start 1.651 -1.778)
			(end -1.651 -1.778)
			(stroke
				(width 0.1524)
				(type default)
			)
			(layer "F.SilkS")
		)
		(fp_line
			(start 1.651 1.778)
			(end 1.651 -1.778)
			(stroke
				(width 0.1524)
				(type default)
			)
			(layer "F.SilkS")
		)
		(fp_poly
			(pts
				(xy -1.778 1.8796) (xy -1.778 -1.8796) (xy 1.778 -1.8796) (xy 1.778 1.8796)
			)
			(stroke
				(width 0)
				(type default)
			)
			(fill no)
			(layer "F.CrtYd")
		)
		(fp_poly
			(pts
				(xy -1.778 1.8796) (xy -1.778 -1.8796) (xy 1.778 -1.8796) (xy 1.778 1.8796)
			)
			(stroke
				(width 0)
				(type default)
			)
			(fill no)
			(layer "F.Fab")
		)
		(pad "D" smd custom
			(at 0 -0.9525)
			(size 0.1905 0.1905)
			(layers "F.Cu" "F.Mask" "F.Paste")
			(net "SSD_ACT_DR7_MOS_N")
			(options
				(clearance outline)
				(anchor circle)
			)
			(primitives
				(gr_poly
					(pts
						(arc
							(start -0.1778 0.5715)
							(mid -0.321484 0.511984)
							(end -0.381 0.3683)
						)
						(arc
							(start -0.381 -0.3683)
							(mid -0.321484 -0.511984)
							(end -0.1778 -0.5715)
						)
						(arc
							(start 0.1778 -0.5715)
							(mid 0.321484 -0.511984)
							(end 0.381 -0.3683)
						)
						(arc
							(start 0.381 0.3683)
							(mid 0.321484 0.511984)
							(end 0.1778 0.5715)
						)
					)
					(width 0)
					(fill yes)
				)
			)
		)
		(pad "G" smd custom
			(at -0.98425 0.9525)
			(size 0.1905 0.1905)
			(layers "F.Cu" "F.Mask" "F.Paste")
			(net "ATTN_LED_DR7_AND_R")
			(options
				(clearance outline)
				(anchor circle)
			)
			(primitives
				(gr_poly
					(pts
						(arc
							(start -0.1778 0.5715)
							(mid -0.321484 0.511984)
							(end -0.381 0.3683)
						)
						(arc
							(start -0.381 -0.3683)
							(mid -0.321484 -0.511984)
							(end -0.1778 -0.5715)
						)
						(arc
							(start 0.1778 -0.5715)
							(mid 0.321484 -0.511984)
							(end 0.381 -0.3683)
						)
						(arc
							(start 0.381 0.3683)
							(mid 0.321484 0.511984)
							(end 0.1778 0.5715)
						)
					)
					(width 0)
					(fill yes)
				)
			)
		)
		(pad "S" smd custom
			(at 0.98425 0.9525)
			(size 0.1905 0.1905)
			(layers "F.Cu" "F.Mask" "F.Paste")
			(net "SSD_ACT_DR7_R")
			(options
				(clearance outline)
				(anchor circle)
			)
			(primitives
				(gr_poly
					(pts
						(arc
							(start -0.1778 0.5715)
							(mid -0.321484 0.511984)
							(end -0.381 0.3683)
						)
						(arc
							(start -0.381 -0.3683)
							(mid -0.321484 -0.511984)
							(end -0.1778 -0.5715)
						)
						(arc
							(start 0.1778 -0.5715)
							(mid 0.321484 -0.511984)
							(end 0.381 -0.3683)
						)
						(arc
							(start 0.381 0.3683)
							(mid 0.321484 0.511984)
							(end 0.1778 0.5715)
						)
					)
					(width 0)
					(fill yes)
				)
			)
		)
	)
	(footprint ""
		(layer "F.Cu")
		(at 77.343 -211.2772 180)
		(property "Reference" "R9970"
			(at 0 0 180)
			(layer "F.SilkS")
			(hide yes)
			(effects
				(font
					(size 1.27 1.27)
				)
			)
		)
		(property "Value" "56R2F-1-GP"
			(at 0.064008 -3.993896 180)
			(unlocked yes)
			(layer "F.Fab")
			(hide yes)
			(effects
				(font
					(size 1.016 1.016)
					(thickness 0.1524)
				)
			)
		)
		(property "Device Type" "R402H16"
			(at 0.064008 -5.517896 180)
			(unlocked yes)
			(layer "F.Fab")
			(hide yes)
			(effects
				(font
					(size 1.016 1.016)
					(thickness 0.1524)
				)
			)
		)
		(duplicate_pad_numbers_are_jumpers no)
		(fp_line
			(start 0.508 -0.9398)
			(end -0.508 -0.9398)
			(stroke
				(width 0.1524)
				(type default)
			)
			(layer "F.SilkS")
		)
		(fp_line
			(start -0.508 -0.9398)
			(end -0.508 0.9398)
			(stroke
				(width 0.1524)
				(type default)
			)
			(layer "F.SilkS")
		)
		(fp_rect
			(start -0.508 0.9398)
			(end 0.508 -0.9398)
			(stroke
				(width 0)
				(type default)
			)
			(fill no)
			(layer "F.CrtYd")
		)
		(fp_rect
			(start -0.508 0.9398)
			(end 0.508 -0.9398)
			(stroke
				(width 0)
				(type default)
			)
			(fill no)
			(layer "F.Fab")
		)
		(pad "1" smd custom
			(at 0 -0.4445 180)
			(size 0.1397 0.1397)
			(layers "F.Cu" "F.Mask" "F.Paste")
			(net "PE_100M_CLK2_P")
			(options
				(clearance outline)
				(anchor circle)
			)
			(primitives
				(gr_poly
					(pts
						(arc
							(start -0.1778 -0.2794)
							(mid -0.249642 -0.249642)
							(end -0.2794 -0.1778)
						)
						(arc
							(start -0.2794 0.1778)
							(mid -0.249642 0.249642)
							(end -0.1778 0.2794)
						)
						(arc
							(start 0.1778 0.2794)
							(mid 0.249642 0.249642)
							(end 0.2794 0.1778)
						)
						(arc
							(start 0.2794 -0.1778)
							(mid 0.249642 -0.249642)
							(end 0.1778 -0.2794)
						)
					)
					(width 0)
					(fill yes)
				)
			)
		)
		(pad "2" smd custom
			(at 0 0.4445 180)
			(size 0.1397 0.1397)
			(layers "F.Cu" "F.Mask" "F.Paste")
			(net "GND")
			(options
				(clearance outline)
				(anchor circle)
			)
			(primitives
				(gr_poly
					(pts
						(arc
							(start -0.1778 -0.2794)
							(mid -0.249642 -0.249642)
							(end -0.2794 -0.1778)
						)
						(arc
							(start -0.2794 0.1778)
							(mid -0.249642 0.249642)
							(end -0.1778 0.2794)
						)
						(arc
							(start 0.1778 0.2794)
							(mid 0.249642 0.249642)
							(end 0.2794 0.1778)
						)
						(arc
							(start 0.2794 -0.1778)
							(mid 0.249642 -0.249642)
							(end 0.1778 -0.2794)
						)
					)
					(width 0)
					(fill yes)
				)
			)
		)
	)
	(footprint ""
		(layer "F.Cu")
		(at 217.043 -287.528 -90)
		(property "Reference" "R391"
			(at 0 0 270)
			(layer "F.SilkS")
			(hide yes)
			(effects
				(font
					(size 1.27 1.27)
				)
			)
		)
		(property "Value" "0R2J-2-GP"
			(at 0.064008 -3.993896 270)
			(unlocked yes)
			(layer "F.Fab")
			(hide yes)
			(effects
				(font
					(size 1.016 1.016)
					(thickness 0.1524)
				)
			)
		)
		(property "Device Type" "R402H16"
			(at 0.064008 -5.517896 270)
			(unlocked yes)
			(layer "F.Fab")
			(hide yes)
			(effects
				(font
					(size 1.016 1.016)
					(thickness 0.1524)
				)
			)
		)
		(duplicate_pad_numbers_are_jumpers no)
		(fp_line
			(start -0.508 -0.9398)
			(end -0.508 0.9398)
			(stroke
				(width 0.1524)
				(type default)
			)
			(layer "F.SilkS")
		)
		(fp_line
			(start 0.508 -0.9398)
			(end -0.508 -0.9398)
			(stroke
				(width 0.1524)
				(type default)
			)
			(layer "F.SilkS")
		)
		(fp_rect
			(start -0.508 0.9398)
			(end 0.508 -0.9398)
			(stroke
				(width 0)
				(type default)
			)
			(fill no)
			(layer "F.CrtYd")
		)
		(fp_rect
			(start -0.508 0.9398)
			(end 0.508 -0.9398)
			(stroke
				(width 0)
				(type default)
			)
			(fill no)
			(layer "F.Fab")
		)
		(pad "1" smd custom
			(at 0 -0.4445 270)
			(size 0.1397 0.1397)
			(layers "F.Cu" "F.Mask" "F.Paste")
			(net "SCL_DR2_R")
			(options
				(clearance outline)
				(anchor circle)
			)
			(primitives
				(gr_poly
					(pts
						(arc
							(start -0.1778 -0.2794)
							(mid -0.249642 -0.249642)
							(end -0.2794 -0.1778)
						)
						(arc
							(start -0.2794 0.1778)
							(mid -0.249642 0.249642)
							(end -0.1778 0.2794)
						)
						(arc
							(start 0.1778 0.2794)
							(mid 0.249642 0.249642)
							(end 0.2794 0.1778)
						)
						(arc
							(start 0.2794 -0.1778)
							(mid 0.249642 -0.249642)
							(end 0.1778 -0.2794)
						)
					)
					(width 0)
					(fill yes)
				)
			)
		)
		(pad "2" smd custom
			(at 0 0.4445 270)
			(size 0.1397 0.1397)
			(layers "F.Cu" "F.Mask" "F.Paste")
			(net "SCL_DR2")
			(options
				(clearance outline)
				(anchor circle)
			)
			(primitives
				(gr_poly
					(pts
						(arc
							(start -0.1778 -0.2794)
							(mid -0.249642 -0.249642)
							(end -0.2794 -0.1778)
						)
						(arc
							(start -0.2794 0.1778)
							(mid -0.249642 0.249642)
							(end -0.1778 0.2794)
						)
						(arc
							(start 0.1778 0.2794)
							(mid 0.249642 0.249642)
							(end 0.2794 0.1778)
						)
						(arc
							(start 0.2794 -0.1778)
							(mid 0.249642 -0.249642)
							(end 0.1778 -0.2794)
						)
					)
					(width 0)
					(fill yes)
				)
			)
		)
	)
	(footprint ""
		(layer "F.Cu")
		(at 101.727 -302.768 -90)
		(property "Reference" "R9512"
			(at 0 0 270)
			(layer "F.SilkS")
			(hide yes)
			(effects
				(font
					(size 1.27 1.27)
				)
			)
		)
		(property "Value" "4K7R2F-GP"
			(at 0.064008 -3.993896 270)
			(unlocked yes)
			(layer "F.Fab")
			(hide yes)
			(effects
				(font
					(size 1.016 1.016)
					(thickness 0.1524)
				)
			)
		)
		(property "Device Type" "R402H16"
			(at 0.064008 -5.517896 270)
			(unlocked yes)
			(layer "F.Fab")
			(hide yes)
			(effects
				(font
					(size 1.016 1.016)
					(thickness 0.1524)
				)
			)
		)
		(duplicate_pad_numbers_are_jumpers no)
		(fp_line
			(start -0.508 -0.9398)
			(end -0.508 0.9398)
			(stroke
				(width 0.1524)
				(type default)
			)
			(layer "F.SilkS")
		)
		(fp_line
			(start 0.508 -0.9398)
			(end -0.508 -0.9398)
			(stroke
				(width 0.1524)
				(type default)
			)
			(layer "F.SilkS")
		)
		(fp_rect
			(start -0.508 0.9398)
			(end 0.508 -0.9398)
			(stroke
				(width 0)
				(type default)
			)
			(fill no)
			(layer "F.CrtYd")
		)
		(fp_rect
			(start -0.508 0.9398)
			(end 0.508 -0.9398)
			(stroke
				(width 0)
				(type default)
			)
			(fill no)
			(layer "F.Fab")
		)
		(pad "1" smd custom
			(at 0 -0.4445 270)
			(size 0.1397 0.1397)
			(layers "F.Cu" "F.Mask" "F.Paste")
			(net "P3V3")
			(options
				(clearance outline)
				(anchor circle)
			)
			(primitives
				(gr_poly
					(pts
						(arc
							(start -0.1778 -0.2794)
							(mid -0.249642 -0.249642)
							(end -0.2794 -0.1778)
						)
						(arc
							(start -0.2794 0.1778)
							(mid -0.249642 0.249642)
							(end -0.1778 0.2794)
						)
						(arc
							(start 0.1778 0.2794)
							(mid 0.249642 0.249642)
							(end 0.2794 0.1778)
						)
						(arc
							(start 0.2794 -0.1778)
							(mid 0.249642 -0.249642)
							(end 0.1778 -0.2794)
						)
					)
					(width 0)
					(fill yes)
				)
			)
		)
		(pad "2" smd custom
			(at 0 0.4445 270)
			(size 0.1397 0.1397)
			(layers "F.Cu" "F.Mask" "F.Paste")
			(net "CLK_BUFFER_EU2_VOE_N")
			(options
				(clearance outline)
				(anchor circle)
			)
			(primitives
				(gr_poly
					(pts
						(arc
							(start -0.1778 -0.2794)
							(mid -0.249642 -0.249642)
							(end -0.2794 -0.1778)
						)
						(arc
							(start -0.2794 0.1778)
							(mid -0.249642 0.249642)
							(end -0.1778 0.2794)
						)
						(arc
							(start 0.1778 0.2794)
							(mid 0.249642 0.249642)
							(end 0.2794 0.1778)
						)
						(arc
							(start 0.2794 -0.1778)
							(mid 0.249642 -0.249642)
							(end 0.1778 -0.2794)
						)
					)
					(width 0)
					(fill yes)
				)
			)
		)
	)
	(footprint ""
		(layer "F.Cu")
		(at 93.345 -297.942)
		(property "Reference" "C9424"
			(at 0 0 0)
			(layer "F.SilkS")
			(hide yes)
			(effects
				(font
					(size 1.27 1.27)
				)
			)
		)
		(property "Value" "SCD1U16V2KX-3GP"
			(at 1.1811 -2.7051 0)
			(unlocked yes)
			(layer "F.Fab")
			(hide yes)
			(effects
				(font
					(size 1.016 1.016)
					(thickness 0.1524)
				)
			)
		)
		(property "Device Type" "C402H22"
			(at 1.1811 -4.2291 0)
			(unlocked yes)
			(layer "F.Fab")
			(hide yes)
			(effects
				(font
					(size 1.016 1.016)
					(thickness 0.1524)
				)
			)
		)
		(duplicate_pad_numbers_are_jumpers no)
		(fp_rect
			(start -0.4318 0.9525)
			(end 0.4318 -0.9525)
			(stroke
				(width 0)
				(type default)
			)
			(fill no)
			(layer "F.CrtYd")
		)
		(fp_rect
			(start -0.4318 0.9525)
			(end 0.4318 -0.9525)
			(stroke
				(width 0)
				(type default)
			)
			(fill no)
			(layer "F.Fab")
		)
		(pad "1" smd custom
			(at 0 -0.4445)
			(size 0.1524 0.1524)
			(layers "F.Cu" "F.Mask" "F.Paste")
			(net "VDD_DIFF_2")
			(options
				(clearance outline)
				(anchor circle)
			)
			(primitives
				(gr_poly
					(pts
						(arc
							(start 0.3048 -0.2032)
							(mid 0.275042 -0.275042)
							(end 0.2032 -0.3048)
						)
						(arc
							(start -0.2032 -0.3048)
							(mid -0.275042 -0.275042)
							(end -0.3048 -0.2032)
						)
						(arc
							(start -0.3048 0.2032)
							(mid -0.275042 0.275042)
							(end -0.2032 0.3048)
						)
						(arc
							(start 0.2032 0.3048)
							(mid 0.275042 0.275042)
							(end 0.3048 0.2032)
						)
					)
					(width 0)
					(fill yes)
				)
			)
		)
		(pad "2" smd custom
			(at 0 0.4445)
			(size 0.1524 0.1524)
			(layers "F.Cu" "F.Mask" "F.Paste")
			(net "GND")
			(options
				(clearance outline)
				(anchor circle)
			)
			(primitives
				(gr_poly
					(pts
						(arc
							(start 0.3048 -0.2032)
							(mid 0.275042 -0.275042)
							(end 0.2032 -0.3048)
						)
						(arc
							(start -0.2032 -0.3048)
							(mid -0.275042 -0.275042)
							(end -0.3048 -0.2032)
						)
						(arc
							(start -0.3048 0.2032)
							(mid -0.275042 0.275042)
							(end -0.2032 0.3048)
						)
						(arc
							(start 0.2032 0.3048)
							(mid 0.275042 0.275042)
							(end 0.3048 0.2032)
						)
					)
					(width 0)
					(fill yes)
				)
			)
		)
	)
)
